(kicad_pcb
	(version 20241229)
	(generator "pcbnew")
	(generator_version "9.0")
	(general
		(thickness 1.63)
		(legacy_teardrops no)
	)
	(paper "A4")
	(title_block
		(title "CM4 Baseboard")
		(date "2026-01-05")
		(rev "1.1.1")
		(company "Antmicro Ltd")
		(comment 1 "www.antmicro.com")
		(comment 9 "footprints 57-59 of 506")
	)
	(layers
		(0 "F.Cu" signal)
		(4 "In1.Cu" power)
		(6 "In2.Cu" power)
		(8 "In3.Cu" signal)
		(10 "In4.Cu" signal)
		(2 "B.Cu" signal)
		(9 "F.Adhes" user "F.Adhesive")
		(11 "B.Adhes" user "B.Adhesive")
		(13 "F.Paste" user)
		(15 "B.Paste" user)
		(5 "F.SilkS" user "F.Silkscreen")
		(7 "B.SilkS" user "B.Silkscreen")
		(1 "F.Mask" user)
		(3 "B.Mask" user)
		(17 "Dwgs.User" user "User.Drawings")
		(19 "Cmts.User" user "User.Comments")
		(21 "Eco1.User" user "User.Eco1")
		(23 "Eco2.User" user "User.Eco2")
		(25 "Edge.Cuts" user)
		(27 "Margin" user)
		(31 "F.CrtYd" user "F.Courtyard")
		(29 "B.CrtYd" user "B.Courtyard")
		(35 "F.Fab" user)
		(33 "B.Fab" user)
	)
	(footprint "antmicro-footprints:SOT-523"
		(layer "F.Cu")
		(at 90.692962 157.6915 90)
		(property "Reference" "Q213"
			(at -2.075 -1.005 180)
			(layer "F.SilkS")
			(effects
				(font
					(size 0.7 0.7)
					(thickness 0.15)
				)
				(justify left bottom)
			)
		)
		(property "Value" "PJE138K"
			(at 0.1 1.824 90)
			(layer "F.Fab")
			(effects
				(font
					(size 0.7 0.7)
					(thickness 0.15)
				)
				(justify left bottom)
			)
		)
		(property "Datasheet" "https://www.mouser.com/datasheet/2/1057/PJE138K-1876698.pdf"
			(at 0 0 90)
			(layer "F.Fab")
			(hide yes)
			(effects
				(font
					(size 1.27 1.27)
					(thickness 0.15)
				)
			)
		)
		(property "MPN" "PJE138K_R1_00001"
			(at 0 0 90)
			(unlocked yes)
			(layer "F.Fab")
			(hide yes)
			(effects
				(font
					(size 1 1)
					(thickness 0.15)
				)
			)
		)
		(property "Manufacturer" "PANJIT"
			(at 0 0 90)
			(unlocked yes)
			(layer "F.Fab")
			(hide yes)
			(effects
				(font
					(size 1 1)
					(thickness 0.15)
				)
			)
		)
		(property "Author" "Antmicro"
			(at 0 0 90)
			(unlocked yes)
			(layer "F.Fab")
			(hide yes)
			(effects
				(font
					(size 1 1)
					(thickness 0.15)
				)
			)
		)
		(property "License" "Apache-2.0"
			(at 0 0 90)
			(unlocked yes)
			(layer "F.Fab")
			(hide yes)
			(effects
				(font
					(size 1 1)
					(thickness 0.15)
				)
			)
		)
		(sheetname "/Compute module/")
		(sheetfile "compute-module.kicad_sch")
		(attr smd)
		(fp_line
			(start -0.277 -0.551)
			(end -0.277 -0.75)
			(stroke
				(width 0.15)
				(type solid)
			)
			(layer "F.SilkS")
		)
		(fp_line
			(start -0.725 -0.551)
			(end -0.277 -0.551)
			(stroke
				(width 0.15)
				(type solid)
			)
			(layer "F.SilkS")
		)
		(fp_line
			(start -0.927 -0.351)
			(end -0.725 -0.551)
			(stroke
				(width 0.15)
				(type solid)
			)
			(layer "F.SilkS")
		)
		(fp_line
			(start -0.927 -0.051)
			(end -0.927 -0.351)
			(stroke
				(width 0.15)
				(type solid)
			)
			(layer "F.SilkS")
		)
		(fp_circle
			(center -0.9652 0.9652)
			(end -0.9152 0.9652)
			(stroke
				(width 0.15)
				(type solid)
			)
			(fill yes)
			(layer "F.SilkS")
		)
		(fp_line
			(start 1.1 -1.16)
			(end 1.1 1.15)
			(stroke
				(width 0.05)
				(type solid)
			)
			(layer "F.CrtYd")
		)
		(fp_line
			(start -1.12 -1.16)
			(end 1.1 -1.16)
			(stroke
				(width 0.05)
				(type solid)
			)
			(layer "F.CrtYd")
		)
		(fp_line
			(start -1.12 -1.16)
			(end -1.12 1.15)
			(stroke
				(width 0.05)
				(type solid)
			)
			(layer "F.CrtYd")
		)
		(fp_line
			(start -1.12 1.15)
			(end 1.1 1.15)
			(stroke
				(width 0.05)
				(type solid)
			)
			(layer "F.CrtYd")
		)
		(fp_line
			(start 0.8 -0.425)
			(end -0.652 -0.425)
			(stroke
				(width 0.15)
				(type solid)
			)
			(layer "F.Fab")
		)
		(fp_line
			(start 0.8 -0.425)
			(end 0.8 0.424)
			(stroke
				(width 0.15)
				(type solid)
			)
			(layer "F.Fab")
		)
		(fp_line
			(start -0.652 -0.425)
			(end -0.802 -0.276)
			(stroke
				(width 0.15)
				(type solid)
			)
			(layer "F.Fab")
		)
		(fp_line
			(start -0.802 -0.276)
			(end -0.802 0.424)
			(stroke
				(width 0.15)
				(type solid)
			)
			(layer "F.Fab")
		)
		(fp_line
			(start 0.8 0.424)
			(end -0.802 0.424)
			(stroke
				(width 0.15)
				(type solid)
			)
			(layer "F.Fab")
		)
		(fp_circle
			(center -0.9652 0.9652)
			(end -0.9144 0.9652)
			(stroke
				(width 0.15)
				(type solid)
			)
			(fill no)
			(layer "F.Fab")
		)
		(fp_text user "License: Apache-2.0"
			(at -1.12 5.024 90)
			(layer "F.Fab")
			(effects
				(font
					(size 0.7 0.7)
					(thickness 0.15)
				)
				(justify left bottom)
			)
		)
		(fp_text user "Author: Antmicro"
			(at -1.12 6.224 90)
			(layer "F.Fab")
			(effects
				(font
					(size 0.7 0.7)
					(thickness 0.15)
				)
				(justify left bottom)
			)
		)
		(fp_text user "${REFERENCE}"
			(at -1.12 3.824 90)
			(layer "F.Fab")
			(effects
				(font
					(size 0.7 0.7)
					(thickness 0.15)
				)
				(justify left bottom)
			)
		)
		(pad "1" smd rect
			(at -0.5 0.65 90)
			(size 0.4 0.51)
			(layers "F.Cu" "F.Mask" "F.Paste")
			(net 347 "/Compute module/ExpanderINT")
			(pinfunction "G")
			(pintype "input")
		)
		(pad "2" smd rect
			(at 0.498 0.65 90)
			(size 0.4 0.51)
			(layers "F.Cu" "F.Mask" "F.Paste")
			(net 3 "GND")
			(pinfunction "S")
			(pintype "passive")
		)
		(pad "3" smd rect
			(at 0 -0.652 90)
			(size 0.4 0.51)
			(layers "F.Cu" "F.Mask" "F.Paste")
			(net 235 "/Compute module/GPIO.23")
			(pinfunction "D")
			(pintype "passive")
		)
	)
	(footprint "antmicro-footprints:Resonator_SMD_Murata_XRCGB_2x1.6x0.65mm"
		(layer "F.Cu")
		(at 74.867962 176.7165 90)
		(property "Reference" "Y801"
			(at -1.9035 0.512038 0)
			(layer "F.SilkS")
			(effects
				(font
					(size 0.7 0.7)
					(thickness 0.15)
				)
				(justify left bottom)
			)
		)
		(property "Value" "Resonator_27.12MHz_XRCGB"
			(at 0 2.2 90)
			(layer "F.Fab")
			(effects
				(font
					(size 0.7 0.7)
					(thickness 0.15)
				)
				(justify left bottom)
			)
		)
		(property "Datasheet" "https://www.murata.com/products/productdata/8801078247454/SPEC-XRCGB27M120F3M13R0.pdf?1541043011000"
			(at 0 0 90)
			(layer "F.Fab")
			(hide yes)
			(effects
				(font
					(size 1.27 1.27)
					(thickness 0.15)
				)
			)
		)
		(property "MPN" "XRCGB27M120F3M13R0"
			(at 0 0 90)
			(unlocked yes)
			(layer "F.Fab")
			(hide yes)
			(effects
				(font
					(size 1 1)
					(thickness 0.15)
				)
			)
		)
		(property "Manufacturer" "Murata"
			(at 0 0 90)
			(unlocked yes)
			(layer "F.Fab")
			(hide yes)
			(effects
				(font
					(size 1 1)
					(thickness 0.15)
				)
			)
		)
		(property "Author" "Antmicro"
			(at 0 0 90)
			(unlocked yes)
			(layer "F.Fab")
			(hide yes)
			(effects
				(font
					(size 1 1)
					(thickness 0.15)
				)
			)
		)
		(property "License" "Apache-2.0"
			(at 0 0 90)
			(unlocked yes)
			(layer "F.Fab")
			(hide yes)
			(effects
				(font
					(size 1 1)
					(thickness 0.15)
				)
			)
		)
		(property "Val" "27.12MHz"
			(at 0 0 90)
			(unlocked yes)
			(layer "F.Fab")
			(hide yes)
			(effects
				(font
					(size 1 1)
					(thickness 0.15)
				)
			)
		)
		(property "CLoad" "10pF"
			(at 0 0 90)
			(unlocked yes)
			(layer "F.Fab")
			(hide yes)
			(effects
				(font
					(size 1 1)
					(thickness 0.15)
				)
			)
		)
		(sheetname "/Peripherals/")
		(sheetfile "peripherals.kicad_sch")
		(attr smd)
		(fp_line
			(start -0.4 -1.15)
			(end 0.4 -1.15)
			(stroke
				(width 0.15)
				(type solid)
			)
			(layer "F.SilkS")
		)
		(fp_line
			(start 0.95 0.4)
			(end 0.95 -0.4)
			(stroke
				(width 0.15)
				(type solid)
			)
			(layer "F.SilkS")
		)
		(fp_line
			(start -0.95 0.4)
			(end -0.95 -0.4)
			(stroke
				(width 0.15)
				(type solid)
			)
			(layer "F.SilkS")
		)
		(fp_line
			(start -0.4 1.15)
			(end 0.4 1.15)
			(stroke
				(width 0.15)
				(type solid)
			)
			(layer "F.SilkS")
		)
		(fp_circle
			(center -0.95 -1.15)
			(end -0.9 -1.15)
			(stroke
				(width 0.15)
				(type solid)
			)
			(fill yes)
			(layer "F.SilkS")
		)
		(fp_rect
			(start -1.05 -1.25)
			(end 1.05 1.24)
			(stroke
				(width 0.05)
				(type solid)
			)
			(fill no)
			(layer "F.CrtYd")
		)
		(fp_rect
			(start -0.85 -1.054)
			(end 0.852 1.054)
			(stroke
				(width 0.15)
				(type solid)
			)
			(fill no)
			(layer "F.Fab")
		)
		(fp_text user "License: Apache-2.0"
			(at -1.05 5.8 90)
			(layer "F.Fab")
			(effects
				(font
					(size 0.7 0.7)
					(thickness 0.15)
				)
				(justify left bottom)
			)
		)
		(fp_text user "${REFERENCE}"
			(at -1.05 3.4 90)
			(layer "F.Fab")
			(effects
				(font
					(size 0.7 0.7)
					(thickness 0.15)
				)
				(justify left bottom)
			)
		)
		(fp_text user "Author: Antmicro"
			(at -1.05 4.6 90)
			(layer "F.Fab")
			(effects
				(font
					(size 0.7 0.7)
					(thickness 0.15)
				)
				(justify left bottom)
			)
		)
		(pad "1" smd rect
			(at -0.5 -0.675 90)
			(size 0.7 0.75)
			(layers "F.Cu" "F.Mask" "F.Paste")
			(net 99 "Net-(U801-XTAL2)")
			(pintype "passive")
		)
		(pad "2" smd rect
			(at -0.5 0.675 90)
			(size 0.7 0.75)
			(layers "F.Cu" "F.Mask" "F.Paste")
			(net 3 "GND")
			(pinfunction "SH")
			(pintype "passive")
		)
		(pad "3" smd rect
			(at 0.5 0.675 90)
			(size 0.7 0.75)
			(layers "F.Cu" "F.Mask" "F.Paste")
			(net 108 "Net-(U801-CLK_XTAL1)")
			(pintype "passive")
		)
		(pad "4" smd rect
			(at 0.5 -0.675 90)
			(size 0.7 0.75)
			(layers "F.Cu" "F.Mask" "F.Paste")
			(net 3 "GND")
			(pinfunction "SH")
			(pintype "passive")
		)
	)
	(footprint "antmicro-footprints:R_0402_1005Metric"
		(layer "F.Cu")
		(at 117.88 153.4415 180)
		(descr "Resistor SMD 0402")
		(tags "resistor SMD 0402")
		(property "Reference" "R216"
			(at -3.525 -0.325 180)
			(layer "F.SilkS")
			(effects
				(font
					(size 0.7 0.7)
					(thickness 0.15)
				)
				(justify left bottom)
			)
		)
		(property "Value" "R_0R_0402"
			(at -1.011843 1.772047 180)
			(layer "F.Fab")
			(effects
				(font
					(size 0.7 0.7)
					(thickness 0.15)
				)
				(justify left bottom)
			)
		)
		(property "Datasheet" "https://industrial.panasonic.com/cdbs/www-data/pdf/RDA0000/AOA0000C301.pdf"
			(at 0 0 180)
			(layer "F.Fab")
			(hide yes)
			(effects
				(font
					(size 1.27 1.27)
					(thickness 0.15)
				)
			)
		)
		(property "Manufacturer" "Panasonic"
			(at 0 0 180)
			(unlocked yes)
			(layer "F.Fab")
			(hide yes)
			(effects
				(font
					(size 1 1)
					(thickness 0.15)
				)
			)
		)
		(property "MPN" "ERJ2GE0R00X"
			(at 0 0 180)
			(unlocked yes)
			(layer "F.Fab")
			(hide yes)
			(effects
				(font
					(size 1 1)
					(thickness 0.15)
				)
			)
		)
		(property "Val" "0R"
			(at 0 0 180)
			(unlocked yes)
			(layer "F.Fab")
			(hide yes)
			(effects
				(font
					(size 1 1)
					(thickness 0.15)
				)
			)
		)
		(property "License" "Apache-2.0"
			(at 0 0 180)
			(unlocked yes)
			(layer "F.Fab")
			(hide yes)
			(effects
				(font
					(size 1 1)
					(thickness 0.15)
				)
			)
		)
		(property "Author" "Antmicro"
			(at 0 0 180)
			(unlocked yes)
			(layer "F.Fab")
			(hide yes)
			(effects
				(font
					(size 1 1)
					(thickness 0.15)
				)
			)
		)
		(property "Tolerance" "~"
			(at 0 0 180)
			(unlocked yes)
			(layer "F.Fab")
			(hide yes)
			(effects
				(font
					(size 1 1)
					(thickness 0.15)
				)
			)
		)
		(property "Current" "1A"
			(at 0 0 180)
			(unlocked yes)
			(layer "F.Fab")
			(hide yes)
			(effects
				(font
					(size 1 1)
					(thickness 0.15)
				)
			)
		)
		(sheetname "/Compute module/")
		(sheetfile "compute-module.kicad_sch")
		(attr smd)
		(fp_rect
			(start -0.925 -0.47)
			(end 0.925 0.47)
			(stroke
				(width 0.05)
				(type default)
			)
			(fill no)
			(layer "F.CrtYd")
		)
		(fp_rect
			(start -0.5 -0.25)
			(end 0.5 0.25)
			(stroke
				(width 0.15)
				(type solid)
			)
			(fill no)
			(layer "F.Fab")
		)
		(fp_text user "Author: Antmicro"
			(at -0.95 4.169 180)
			(layer "F.Fab")
			(effects
				(font
					(size 0.7 0.7)
					(thickness 0.15)
				)
				(justify left bottom)
			)
		)
		(fp_text user "License: Apache-2.0"
			(at -0.95 5.169 180)
			(layer "F.Fab")
			(effects
				(font
					(size 0.7 0.7)
					(thickness 0.15)
				)
				(justify left bottom)
			)
		)
		(fp_text user "${REFERENCE}"
			(at -0.95 3.168 180)
			(layer "F.Fab")
			(effects
				(font
					(size 0.7 0.7)
					(thickness 0.15)
				)
				(justify left bottom)
			)
		)
		(pad "1" smd roundrect
			(at -0.48 0 180)
			(size 0.59 0.64)
			(layers "F.Cu" "F.Mask" "F.Paste")
			(roundrect_rratio 0.25)
			(net 169 "/Compute module/NVMe.TX1_P")
			(pintype "passive")
		)
		(pad "2" smd roundrect
			(at 0.48 0 180)
			(size 0.59 0.64)
			(layers "F.Cu" "F.Mask" "F.Paste")
			(roundrect_rratio 0.25)
			(net 139 "/Compute module/T1_P")
			(pintype "passive")
		)
	)
)
